# T6G (Grand Teton) — schematic netlist excerpt (pin names and nets, part order shuffled) for the footprints in the layout excerpt that follows; sources: Cadence DE-HDL packaged netlist, KiCad conversion of 04192023_DAF0TMB3IC0_F0TG_MB_C_brd_V02_OCP.brd

PC2215  Q_CAP  3900PF 50V 10% X7R  pkg C0402  page 146 : A = P12V_E1S_GATE_0 ; B = GND
C931  Q_CAP_DIFFBUS  DIFF BUS_0.22UF 6.3V 20% X6S  pkg C0201  page 63 : \1\ = P5E_CPU0_P0_TX_C_DP<1> ; \2\ = P5E_CPU0_P0_TX_DP<1>
R6119  Q_RES  0 5% CHIP  pkg 0402LF  page 269 : A = PWRGD_P3V3_AUX ; B = P1V8_AUX_ENABLE

(kicad_pcb
	(version 20260206)
	(generator "pcbnew")
	(generator_version "10.0")
	(general
		(thickness 1.6)
		(legacy_teardrops no)
	)
	(paper "A4")
	(title_block
		(title "04192023_DAF0TMB3IC0_F0TG_MB_C_brd_V02_OCP.brd")
		(comment 1 "Grand Teton / footprints 503-505 of 8354")
	)
	(layers
		(0 "F.Cu" signal "TOP")
		(4 "In1.Cu" signal "GND")
		(6 "In2.Cu" signal "IN1")
		(8 "In3.Cu" signal "GND1")
		(10 "In4.Cu" signal "IN2")
		(12 "In5.Cu" signal "GND2")
		(14 "In6.Cu" signal "IN3")
		(16 "In7.Cu" signal "GND3")
		(18 "In8.Cu" signal "VCC")
		(20 "In9.Cu" signal "VCC1")
		(22 "In10.Cu" signal "GND4")
		(24 "In11.Cu" signal "IN4")
		(26 "In12.Cu" signal "GND5")
		(28 "In13.Cu" signal "IN5")
		(30 "In14.Cu" signal "GND6")
		(32 "In15.Cu" signal "IN6")
		(34 "In16.Cu" signal "GND7")
		(2 "B.Cu" signal "BOTTOM")
		(9 "F.Adhes" user "F.Adhesive")
		(11 "B.Adhes" user "B.Adhesive")
		(13 "F.Paste" user "Package Geometry/Pastemask Top")
		(15 "B.Paste" user "Package Geometry/Pastemask Bottom")
		(5 "F.SilkS" user "Ref Des/Silkscreen Top")
		(7 "B.SilkS" user "Ref Des/Silkscreen Bottom")
		(1 "F.Mask" user "Board Geometry/Soldermask Top")
		(3 "B.Mask" user "Board Geometry/Soldermask Bottom")
		(17 "Dwgs.User" user "User.Drawings")
		(19 "Cmts.User" user "User.Comments")
		(21 "Eco1.User" user "User.Eco1")
		(23 "Eco2.User" user "User.Eco2")
		(25 "Edge.Cuts" user "Board Geometry/Outline")
		(27 "Margin" user)
		(31 "F.CrtYd" user "Package Geometry/Place Bound Top")
		(29 "B.CrtYd" user "Package Geometry/Place Bound Bottom")
		(35 "F.Fab" user "Ref Des/Assembly Top")
		(33 "B.Fab" user "Ref Des/Assembly Bottom")
	)
	(footprint ""
		(layer "F.Cu")
		(at 255.45669 -40.498522 -90)
		(property "Reference" "PC2215"
			(at 0 0 270)
			(layer "F.SilkS")
			(hide yes)
			(effects
				(font
					(size 1.27 1.27)
				)
			)
		)
		(property "Value" ""
			(at 0 0 270)
			(layer "F.Fab")
			(effects
				(font
					(size 1.27 1.27)
				)
			)
		)
		(duplicate_pad_numbers_are_jumpers no)
		(fp_line
			(start -0.7874 0.4064)
			(end -0.7874 -0.4064)
			(stroke
				(width 0.1524)
				(type default)
			)
			(layer "F.SilkS")
		)
		(fp_line
			(start 0.7874 0.4064)
			(end -0.7874 0.4064)
			(stroke
				(width 0.1524)
				(type default)
			)
			(layer "F.SilkS")
		)
		(fp_line
			(start -0.7874 -0.4064)
			(end 0.7874 -0.4064)
			(stroke
				(width 0.1524)
				(type default)
			)
			(layer "F.SilkS")
		)
		(fp_line
			(start 0.7874 -0.4064)
			(end 0.7874 0.4064)
			(stroke
				(width 0.1524)
				(type default)
			)
			(layer "F.SilkS")
		)
		(fp_line
			(start -0.67945 0.3048)
			(end -0.67945 -0.305054)
			(stroke
				(width 0.1)
				(type default)
			)
			(layer "F.Fab")
		)
		(fp_line
			(start -0.12065 0.3048)
			(end -0.67945 0.3048)
			(stroke
				(width 0.1)
				(type default)
			)
			(layer "F.Fab")
		)
		(fp_line
			(start 0.120396 0.3048)
			(end 0.120396 0.2794)
			(stroke
				(width 0.1)
				(type default)
			)
			(layer "F.Fab")
		)
		(fp_line
			(start 0.67945 0.3048)
			(end 0.120396 0.3048)
			(stroke
				(width 0.1)
				(type default)
			)
			(layer "F.Fab")
		)
		(fp_line
			(start -0.12065 0.2794)
			(end -0.12065 0.3048)
			(stroke
				(width 0.1)
				(type default)
			)
			(layer "F.Fab")
		)
		(fp_line
			(start 0.120396 0.2794)
			(end -0.12065 0.2794)
			(stroke
				(width 0.1)
				(type default)
			)
			(layer "F.Fab")
		)
		(fp_line
			(start -0.12065 -0.2794)
			(end 0.12065 -0.2794)
			(stroke
				(width 0.1)
				(type default)
			)
			(layer "F.Fab")
		)
		(fp_line
			(start 0.12065 -0.2794)
			(end 0.12065 -0.3048)
			(stroke
				(width 0.1)
				(type default)
			)
			(layer "F.Fab")
		)
		(fp_line
			(start 0.12065 -0.3048)
			(end 0.67945 -0.3048)
			(stroke
				(width 0.1)
				(type default)
			)
			(layer "F.Fab")
		)
		(fp_line
			(start 0.67945 -0.3048)
			(end 0.67945 0.3048)
			(stroke
				(width 0.1)
				(type default)
			)
			(layer "F.Fab")
		)
		(fp_line
			(start -0.67945 -0.305054)
			(end -0.12065 -0.305054)
			(stroke
				(width 0.1)
				(type default)
			)
			(layer "F.Fab")
		)
		(fp_line
			(start -0.12065 -0.305054)
			(end -0.12065 -0.2794)
			(stroke
				(width 0.1)
				(type default)
			)
			(layer "F.Fab")
		)
		(pad "1" smd circle
			(at -0.40005 0 270)
			(size 0 0)
			(layers "F.Cu" "F.Mask" "F.Paste")
			(net "P12V_E1S_GATE_0")
		)
		(pad "2" smd circle
			(at 0.40005 0 270)
			(size 0 0)
			(layers "F.Cu" "F.Mask" "F.Paste")
			(net "GND")
		)
	)
	(footprint ""
		(layer "F.Cu")
		(at 298.967144 -384.32486 180)
		(property "Reference" "C931"
			(at 0 0 180)
			(layer "F.SilkS")
			(hide yes)
			(effects
				(font
					(size 1.27 1.27)
				)
			)
		)
		(property "Value" ""
			(at 0 0 180)
			(layer "F.Fab")
			(effects
				(font
					(size 1.27 1.27)
				)
			)
		)
		(duplicate_pad_numbers_are_jumpers no)
		(fp_line
			(start 0.299974 0.150114)
			(end -0.299974 0.150114)
			(stroke
				(width 0.1)
				(type default)
			)
			(layer "F.Fab")
		)
		(fp_line
			(start 0.299974 -0.150114)
			(end 0.299974 0.150114)
			(stroke
				(width 0.1)
				(type default)
			)
			(layer "F.Fab")
		)
		(fp_line
			(start -0.299974 0.150114)
			(end -0.299974 -0.150114)
			(stroke
				(width 0.1)
				(type default)
			)
			(layer "F.Fab")
		)
		(fp_line
			(start -0.299974 -0.150114)
			(end 0.299974 -0.150114)
			(stroke
				(width 0.1)
				(type default)
			)
			(layer "F.Fab")
		)
		(pad "1" smd rect
			(at -0.2667 0 180)
			(size 0.3048 0.381)
			(layers "F.Cu" "F.Mask" "F.Paste")
			(net "P5E_CPU0_P0_TX_C_DP<1>")
		)
		(pad "2" smd rect
			(at 0.2667 0 180)
			(size 0.3048 0.381)
			(layers "F.Cu" "F.Mask" "F.Paste")
			(net "P5E_CPU0_P0_TX_DP<1>")
		)
	)
	(footprint ""
		(layer "F.Cu")
		(at 216.982548 -133.200902 180)
		(property "Reference" "R6119"
			(at 0 0 180)
			(layer "F.SilkS")
			(hide yes)
			(effects
				(font
					(size 1.27 1.27)
				)
			)
		)
		(property "Value" ""
			(at 0 0 180)
			(layer "F.Fab")
			(effects
				(font
					(size 1.27 1.27)
				)
			)
		)
		(duplicate_pad_numbers_are_jumpers no)
		(fp_line
			(start 0.7874 0.4064)
			(end -0.7874 0.4064)
			(stroke
				(width 0.1524)
				(type default)
			)
			(layer "F.SilkS")
		)
		(fp_line
			(start 0.7874 -0.4064)
			(end 0.7874 0.4064)
			(stroke
				(width 0.1524)
				(type default)
			)
			(layer "F.SilkS")
		)
		(fp_line
			(start -0.7874 0.4064)
			(end -0.7874 -0.4064)
			(stroke
				(width 0.1524)
				(type default)
			)
			(layer "F.SilkS")
		)
		(fp_line
			(start -0.7874 -0.4064)
			(end 0.7874 -0.4064)
			(stroke
				(width 0.1524)
				(type default)
			)
			(layer "F.SilkS")
		)
		(fp_line
			(start 0.67945 0.3048)
			(end 0.120396 0.3048)
			(stroke
				(width 0.1)
				(type default)
			)
			(layer "F.Fab")
		)
		(fp_line
			(start 0.67945 -0.3048)
			(end 0.67945 0.3048)
			(stroke
				(width 0.1)
				(type default)
			)
			(layer "F.Fab")
		)
		(fp_line
			(start 0.12065 -0.2794)
			(end 0.12065 -0.3048)
			(stroke
				(width 0.1)
				(type default)
			)
			(layer "F.Fab")
		)
		(fp_line
			(start 0.12065 -0.3048)
			(end 0.67945 -0.3048)
			(stroke
				(width 0.1)
				(type default)
			)
			(layer "F.Fab")
		)
		(fp_line
			(start 0.120396 0.3048)
			(end 0.120396 0.2794)
			(stroke
				(width 0.1)
				(type default)
			)
			(layer "F.Fab")
		)
		(fp_line
			(start 0.120396 0.2794)
			(end -0.12065 0.2794)
			(stroke
				(width 0.1)
				(type default)
			)
			(layer "F.Fab")
		)
		(fp_line
			(start -0.12065 0.3048)
			(end -0.67945 0.3048)
			(stroke
				(width 0.1)
				(type default)
			)
			(layer "F.Fab")
		)
		(fp_line
			(start -0.12065 0.2794)
			(end -0.12065 0.3048)
			(stroke
				(width 0.1)
				(type default)
			)
			(layer "F.Fab")
		)
		(fp_line
			(start -0.12065 -0.2794)
			(end 0.12065 -0.2794)
			(stroke
				(width 0.1)
				(type default)
			)
			(layer "F.Fab")
		)
		(fp_line
			(start -0.12065 -0.305054)
			(end -0.12065 -0.2794)
			(stroke
				(width 0.1)
				(type default)
			)
			(layer "F.Fab")
		)
		(fp_line
			(start -0.67945 0.3048)
			(end -0.67945 -0.305054)
			(stroke
				(width 0.1)
				(type default)
			)
			(layer "F.Fab")
		)
		(fp_line
			(start -0.67945 -0.305054)
			(end -0.12065 -0.305054)
			(stroke
				(width 0.1)
				(type default)
			)
			(layer "F.Fab")
		)
		(pad "1" smd circle
			(at -0.40005 0 180)
			(size 0 0)
			(layers "F.Cu" "F.Mask" "F.Paste")
			(net "PWRGD_P3V3_AUX")
		)
		(pad "2" smd circle
			(at 0.40005 0 180)
			(size 0 0)
			(layers "F.Cu" "F.Mask" "F.Paste")
			(net "P1V8_AUX_ENABLE")
		)
	)
)
